# S9S_MB_2U (Grand Teton) — schematic netlist excerpt (pin names and nets, part order shuffled) for the footprints in the layout excerpt that follows; sources: Cadence DE-HDL packaged netlist, KiCad conversion of 03242023_DA0F0TMBIJ0_F0T_Motherboard_J_brd_V01_OCP.brd

PC100  Q_CAP  470PF 50V 10% X7R  pkg 0402  page 266 : A = PVCCFA_EHV_FIVRA_CPU0_BTSEN ; B = GND
PR4524  Q_RES  10M 1% EMPTY  pkg 0402LF  page 156 : A = P12V_OCP_SFF ; B = P12V_OCP_GATE_1

(kicad_pcb
	(version 20260206)
	(generator "pcbnew")
	(generator_version "10.0")
	(general
		(thickness 1.6)
		(legacy_teardrops no)
	)
	(paper "A4")
	(title_block
		(title "03242023_DA0F0TMBIJ0_F0T_Motherboard_J_brd_V01_OCP.brd")
		(comment 1 "Grand Teton / footprints 1619-1620 of 6105")
	)
	(layers
		(0 "F.Cu" signal "TOP")
		(4 "In1.Cu" signal "GND")
		(6 "In2.Cu" signal "IN1")
		(8 "In3.Cu" signal "GND1")
		(10 "In4.Cu" signal "IN2")
		(12 "In5.Cu" signal "GND2")
		(14 "In6.Cu" signal "IN3")
		(16 "In7.Cu" signal "GND3")
		(18 "In8.Cu" signal "VCC")
		(20 "In9.Cu" signal "VCC1")
		(22 "In10.Cu" signal "GND4")
		(24 "In11.Cu" signal "IN4")
		(26 "In12.Cu" signal "GND5")
		(28 "In13.Cu" signal "IN5")
		(30 "In14.Cu" signal "GND6")
		(32 "In15.Cu" signal "IN6")
		(34 "In16.Cu" signal "GND7")
		(2 "B.Cu" signal "BOTTOM")
		(9 "F.Adhes" user "F.Adhesive")
		(11 "B.Adhes" user "B.Adhesive")
		(13 "F.Paste" user "Package Geometry/Pastemask Top")
		(15 "B.Paste" user "Package Geometry/Pastemask Bottom")
		(5 "F.SilkS" user "Ref Des/Silkscreen Top")
		(7 "B.SilkS" user "Ref Des/Silkscreen Bottom")
		(1 "F.Mask" user "Board Geometry/Soldermask Top")
		(3 "B.Mask" user "Board Geometry/Soldermask Bottom")
		(17 "Dwgs.User" user "User.Drawings")
		(19 "Cmts.User" user "User.Comments")
		(21 "Eco1.User" user "User.Eco1")
		(23 "Eco2.User" user "User.Eco2")
		(25 "Edge.Cuts" user "Board Geometry/Outline")
		(27 "Margin" user)
		(31 "F.CrtYd" user "Package Geometry/Place Bound Top")
		(29 "B.CrtYd" user "Package Geometry/Place Bound Bottom")
		(35 "F.Fab" user "Ref Des/Assembly Top")
		(33 "B.Fab" user "Ref Des/Assembly Bottom")
	)
	(footprint ""
		(layer "F.Cu")
		(at 453.043544 -25.638506 180)
		(property "Reference" "PR4524"
			(at 0 0 180)
			(layer "F.SilkS")
			(hide yes)
			(effects
				(font
					(size 1.27 1.27)
				)
			)
		)
		(property "Value" ""
			(at 0 0 180)
			(layer "F.Fab")
			(effects
				(font
					(size 1.27 1.27)
				)
			)
		)
		(duplicate_pad_numbers_are_jumpers no)
		(fp_line
			(start 0.7874 0.4064)
			(end -0.7874 0.4064)
			(stroke
				(width 0.1524)
				(type default)
			)
			(layer "F.SilkS")
		)
		(fp_line
			(start 0.7874 -0.4064)
			(end 0.7874 0.4064)
			(stroke
				(width 0.1524)
				(type default)
			)
			(layer "F.SilkS")
		)
		(fp_line
			(start -0.7874 0.4064)
			(end -0.7874 -0.4064)
			(stroke
				(width 0.1524)
				(type default)
			)
			(layer "F.SilkS")
		)
		(fp_line
			(start -0.7874 -0.4064)
			(end 0.7874 -0.4064)
			(stroke
				(width 0.1524)
				(type default)
			)
			(layer "F.SilkS")
		)
		(fp_line
			(start 0.67945 0.3048)
			(end 0.120396 0.3048)
			(stroke
				(width 0.1)
				(type default)
			)
			(layer "F.Fab")
		)
		(fp_line
			(start 0.67945 -0.3048)
			(end 0.67945 0.3048)
			(stroke
				(width 0.1)
				(type default)
			)
			(layer "F.Fab")
		)
		(fp_line
			(start 0.12065 -0.2794)
			(end 0.12065 -0.3048)
			(stroke
				(width 0.1)
				(type default)
			)
			(layer "F.Fab")
		)
		(fp_line
			(start 0.12065 -0.3048)
			(end 0.67945 -0.3048)
			(stroke
				(width 0.1)
				(type default)
			)
			(layer "F.Fab")
		)
		(fp_line
			(start 0.120396 0.3048)
			(end 0.120396 0.2794)
			(stroke
				(width 0.1)
				(type default)
			)
			(layer "F.Fab")
		)
		(fp_line
			(start 0.120396 0.2794)
			(end -0.12065 0.2794)
			(stroke
				(width 0.1)
				(type default)
			)
			(layer "F.Fab")
		)
		(fp_line
			(start -0.12065 0.3048)
			(end -0.67945 0.3048)
			(stroke
				(width 0.1)
				(type default)
			)
			(layer "F.Fab")
		)
		(fp_line
			(start -0.12065 0.2794)
			(end -0.12065 0.3048)
			(stroke
				(width 0.1)
				(type default)
			)
			(layer "F.Fab")
		)
		(fp_line
			(start -0.12065 -0.2794)
			(end 0.12065 -0.2794)
			(stroke
				(width 0.1)
				(type default)
			)
			(layer "F.Fab")
		)
		(fp_line
			(start -0.12065 -0.305054)
			(end -0.12065 -0.2794)
			(stroke
				(width 0.1)
				(type default)
			)
			(layer "F.Fab")
		)
		(fp_line
			(start -0.67945 0.3048)
			(end -0.67945 -0.305054)
			(stroke
				(width 0.1)
				(type default)
			)
			(layer "F.Fab")
		)
		(fp_line
			(start -0.67945 -0.305054)
			(end -0.12065 -0.305054)
			(stroke
				(width 0.1)
				(type default)
			)
			(layer "F.Fab")
		)
		(pad "1" smd circle
			(at -0.40005 0 180)
			(size 0 0)
			(layers "F.Cu" "F.Mask" "F.Paste")
			(net "P12V_OCP_SFF")
		)
		(pad "2" smd circle
			(at 0.40005 0 180)
			(size 0 0)
			(layers "F.Cu" "F.Mask" "F.Paste")
			(net "P12V_OCP_GATE_1")
		)
	)
	(footprint ""
		(layer "F.Cu")
		(at 362.646468 -358.93375)
		(property "Reference" "PC100"
			(at 0 0 0)
			(layer "F.SilkS")
			(hide yes)
			(effects
				(font
					(size 1.27 1.27)
				)
			)
		)
		(property "Value" ""
			(at 0 0 0)
			(layer "F.Fab")
			(effects
				(font
					(size 1.27 1.27)
				)
			)
		)
		(duplicate_pad_numbers_are_jumpers no)
		(fp_line
			(start -0.7874 -0.4064)
			(end 0.7874 -0.4064)
			(stroke
				(width 0.1524)
				(type default)
			)
			(layer "F.SilkS")
		)
		(fp_line
			(start -0.7874 0.4064)
			(end -0.7874 -0.4064)
			(stroke
				(width 0.1524)
				(type default)
			)
			(layer "F.SilkS")
		)
		(fp_line
			(start 0.7874 -0.4064)
			(end 0.7874 0.4064)
			(stroke
				(width 0.1524)
				(type default)
			)
			(layer "F.SilkS")
		)
		(fp_line
			(start 0.7874 0.4064)
			(end -0.7874 0.4064)
			(stroke
				(width 0.1524)
				(type default)
			)
			(layer "F.SilkS")
		)
		(fp_line
			(start -0.67945 -0.305054)
			(end -0.12065 -0.305054)
			(stroke
				(width 0.1)
				(type default)
			)
			(layer "F.Fab")
		)
		(fp_line
			(start -0.67945 0.3048)
			(end -0.67945 -0.305054)
			(stroke
				(width 0.1)
				(type default)
			)
			(layer "F.Fab")
		)
		(fp_line
			(start -0.12065 -0.305054)
			(end -0.12065 -0.2794)
			(stroke
				(width 0.1)
				(type default)
			)
			(layer "F.Fab")
		)
		(fp_line
			(start -0.12065 -0.2794)
			(end 0.12065 -0.2794)
			(stroke
				(width 0.1)
				(type default)
			)
			(layer "F.Fab")
		)
		(fp_line
			(start -0.12065 0.2794)
			(end -0.12065 0.3048)
			(stroke
				(width 0.1)
				(type default)
			)
			(layer "F.Fab")
		)
		(fp_line
			(start -0.12065 0.3048)
			(end -0.67945 0.3048)
			(stroke
				(width 0.1)
				(type default)
			)
			(layer "F.Fab")
		)
		(fp_line
			(start 0.120396 0.2794)
			(end -0.12065 0.2794)
			(stroke
				(width 0.1)
				(type default)
			)
			(layer "F.Fab")
		)
		(fp_line
			(start 0.120396 0.3048)
			(end 0.120396 0.2794)
			(stroke
				(width 0.1)
				(type default)
			)
			(layer "F.Fab")
		)
		(fp_line
			(start 0.12065 -0.3048)
			(end 0.67945 -0.3048)
			(stroke
				(width 0.1)
				(type default)
			)
			(layer "F.Fab")
		)
		(fp_line
			(start 0.12065 -0.2794)
			(end 0.12065 -0.3048)
			(stroke
				(width 0.1)
				(type default)
			)
			(layer "F.Fab")
		)
		(fp_line
			(start 0.67945 -0.3048)
			(end 0.67945 0.3048)
			(stroke
				(width 0.1)
				(type default)
			)
			(layer "F.Fab")
		)
		(fp_line
			(start 0.67945 0.3048)
			(end 0.120396 0.3048)
			(stroke
				(width 0.1)
				(type default)
			)
			(layer "F.Fab")
		)
		(pad "1" smd circle
			(at -0.40005 0)
			(size 0 0)
			(layers "F.Cu" "F.Mask" "F.Paste")
			(net "PVCCFA_EHV_FIVRA_CPU0_BTSEN")
		)
		(pad "2" smd circle
			(at 0.40005 0)
			(size 0 0)
			(layers "F.Cu" "F.Mask" "F.Paste")
			(net "GND")
		)
	)
)
